# BASEBOARD_FAB2 (Tioga Pass) — schematic netlist excerpt (pin names and nets, part order shuffled) for the footprints in the layout excerpt that follows; sources: Cadence DE-HDL packaged netlist, KiCad conversion of Wiwynn_Tioga_Pass_MB.brd

C5M1  CAP_A  47UF 4V 20% X5R  pkg 0603V  page 220 : A = PVDDQ_DEF ; B = GND
C6U5  CAP_A  0.1UF 16V 10% X7R  pkg 0402V  page 233 : A = VR_FET_SW_P12V_STBY_PVPP_GHJ ; B = GND
C9W1  SC22P50V2JN-4GP  5%  pkg SMD-BCG  page 200 : \1\ = A_P12V_STBY_FP_TRIGGER ; \2\ = AGND_HSC

(kicad_pcb
	(version 20260206)
	(generator "pcbnew")
	(generator_version "10.0")
	(general
		(thickness 1.6)
		(legacy_teardrops no)
	)
	(paper "A4")
	(title_block
		(title "Wiwynn_Tioga_Pass_MB.brd")
		(comment 1 "Tioga Pass / footprints 2473-2475 of 4770")
	)
	(layers
		(0 "F.Cu" signal "TOP")
		(4 "In1.Cu" signal "L2GND")
		(6 "In2.Cu" signal "L3")
		(8 "In3.Cu" signal "L4GND")
		(10 "In4.Cu" signal "L5")
		(12 "In5.Cu" signal "L6GND")
		(14 "In6.Cu" signal "L7VCC")
		(16 "In7.Cu" signal "L8VCC")
		(18 "In8.Cu" signal "L9GND")
		(20 "In9.Cu" signal "L10")
		(22 "In10.Cu" signal "L11GND")
		(24 "In11.Cu" signal "L12")
		(26 "In12.Cu" signal "L13GND")
		(2 "B.Cu" signal "BOTTOM")
		(9 "F.Adhes" user "F.Adhesive")
		(11 "B.Adhes" user "B.Adhesive")
		(13 "F.Paste" user "Package Geometry/Pastemask Top")
		(15 "B.Paste" user "Package Geometry/Pastemask Bottom")
		(5 "F.SilkS" user "Ref Des/Silkscreen Top")
		(7 "B.SilkS" user "Ref Des/Silkscreen Bottom")
		(1 "F.Mask" user "Board Geometry/Soldermask Top")
		(3 "B.Mask" user "Board Geometry/Soldermask Bottom")
		(17 "Dwgs.User" user "User.Drawings")
		(19 "Cmts.User" user "User.Comments")
		(21 "Eco1.User" user "User.Eco1")
		(23 "Eco2.User" user "User.Eco2")
		(25 "Edge.Cuts" user "Board Geometry/Outline")
		(27 "Margin" user)
		(31 "F.CrtYd" user "Package Geometry/Place Bound Top")
		(29 "B.CrtYd" user "Package Geometry/Place Bound Bottom")
		(35 "F.Fab" user "Ref Des/Assembly Top")
		(33 "B.Fab" user "Ref Des/Assembly Bottom")
	)
	(footprint ""
		(layer "B.Cu")
		(at 272.861532 -135.4074 90)
		(property "Reference" "C5M1"
			(at -1.848866 0.752348 90)
			(unlocked yes)
			(layer "B.SilkS")
			(effects
				(font
					(size 1.27 0.9652)
					(thickness 0.1524)
				)
				(justify mirror)
			)
		)
		(property "Value" ""
			(at 0 0 90)
			(layer "B.Fab")
			(effects
				(font
					(size 1.27 1.27)
				)
				(justify mirror)
			)
		)
		(duplicate_pad_numbers_are_jumpers no)
		(fp_rect
			(start 0.500126 1.598422)
			(end -0.500126 -0.201422)
			(stroke
				(width 0)
				(type default)
			)
			(fill no)
			(layer "B.CrtYd")
		)
		(fp_line
			(start 0.500126 -0.201422)
			(end -0.500126 -0.201422)
			(stroke
				(width 0.1)
				(type default)
			)
			(layer "B.Fab")
		)
		(fp_line
			(start -0.500126 -0.201422)
			(end -0.500126 1.598422)
			(stroke
				(width 0.1)
				(type default)
			)
			(layer "B.Fab")
		)
		(fp_line
			(start 0.500126 1.598422)
			(end 0.500126 -0.201422)
			(stroke
				(width 0.1)
				(type default)
			)
			(layer "B.Fab")
		)
		(fp_line
			(start -0.500126 1.598422)
			(end 0.500126 1.598422)
			(stroke
				(width 0.1)
				(type default)
			)
			(layer "B.Fab")
		)
		(pad "1" smd rect
			(at 0 0)
			(size 0.889 0.9906)
			(layers "B.Cu" "B.Mask" "B.Paste")
			(net "PVDDQ_DEF")
		)
		(pad "2" smd rect
			(at 0 1.397)
			(size 0.889 0.9906)
			(layers "B.Cu" "B.Mask" "B.Paste")
			(net "GND")
		)
		(zone
			(layer "B.Cu")
			(hatch none 0.5)
			(connect_pads
				(clearance 0)
			)
			(min_thickness 0.25)
			(keepout
				(tracks not_allowed)
				(vias allowed)
				(pads allowed)
				(copperpour not_allowed)
				(footprints allowed)
			)
			(placement
				(enabled no)
				(sheetname "")
			)
			(fill
				(thermal_gap 0.5)
				(thermal_bridge_width 0.5)
				(island_removal_mode 0)
			)
			(polygon
				(pts
					(xy 273.814032 -135.9027) (xy 273.306032 -135.9027) (xy 273.306032 -134.9121) (xy 273.814032 -134.9121)
				)
			)
		)
		(zone
			(layer "B.Cu")
			(hatch none 0.5)
			(connect_pads
				(clearance 0)
			)
			(min_thickness 0.25)
			(keepout
				(tracks allowed)
				(vias not_allowed)
				(pads allowed)
				(copperpour not_allowed)
				(footprints allowed)
			)
			(placement
				(enabled no)
				(sheetname "")
			)
			(fill
				(thermal_gap 0.5)
				(thermal_bridge_width 0.5)
				(island_removal_mode 0)
			)
			(polygon
				(pts
					(xy 273.814032 -135.9027) (xy 273.306032 -135.9027) (xy 273.306032 -134.9121) (xy 273.814032 -134.9121)
				)
			)
		)
	)
	(footprint ""
		(layer "B.Cu")
		(at 181.991 -12.7 180)
		(property "Reference" "C6U5"
			(at 0 0 0)
			(layer "B.SilkS")
			(hide yes)
			(effects
				(font
					(size 1.27 1.27)
				)
				(justify mirror)
			)
		)
		(property "Value" ""
			(at 0 0 0)
			(layer "B.Fab")
			(effects
				(font
					(size 1.27 1.27)
				)
				(justify mirror)
			)
		)
		(duplicate_pad_numbers_are_jumpers no)
		(fp_rect
			(start 0.3048 -0.1016)
			(end -0.3048 0.9906)
			(stroke
				(width 0)
				(type default)
			)
			(fill no)
			(layer "B.CrtYd")
		)
		(fp_line
			(start 0.3048 0.9906)
			(end -0.3048 0.9906)
			(stroke
				(width 0.1)
				(type default)
			)
			(layer "B.Fab")
		)
		(fp_line
			(start 0.3048 -0.1016)
			(end 0.3048 0.9906)
			(stroke
				(width 0.1)
				(type default)
			)
			(layer "B.Fab")
		)
		(fp_line
			(start -0.3048 0.9906)
			(end -0.3048 -0.1016)
			(stroke
				(width 0.1)
				(type default)
			)
			(layer "B.Fab")
		)
		(fp_line
			(start -0.3048 -0.1016)
			(end 0.3048 -0.1016)
			(stroke
				(width 0.1)
				(type default)
			)
			(layer "B.Fab")
		)
		(pad "1" smd rect
			(at 0 0)
			(size 0.508 0.508)
			(layers "B.Cu" "B.Mask" "B.Paste")
			(net "VR_FET_SW_P12V_STBY_PVPP_GHJ")
		)
		(pad "2" smd rect
			(at 0 0.889)
			(size 0.508 0.508)
			(layers "B.Cu" "B.Mask" "B.Paste")
			(net "GND")
		)
		(zone
			(layer "B.Cu")
			(hatch none 0.5)
			(connect_pads
				(clearance 0)
			)
			(min_thickness 0.25)
			(keepout
				(tracks allowed)
				(vias not_allowed)
				(pads allowed)
				(copperpour not_allowed)
				(footprints allowed)
			)
			(placement
				(enabled no)
				(sheetname "")
			)
			(fill
				(thermal_gap 0.5)
				(thermal_bridge_width 0.5)
				(island_removal_mode 0)
			)
			(polygon
				(pts
					(xy 181.737 -12.954) (xy 182.245 -12.954) (xy 182.245 -13.335) (xy 181.737 -13.335)
				)
			)
		)
		(zone
			(layer "B.Cu")
			(hatch none 0.5)
			(connect_pads
				(clearance 0)
			)
			(min_thickness 0.25)
			(keepout
				(tracks not_allowed)
				(vias allowed)
				(pads allowed)
				(copperpour not_allowed)
				(footprints allowed)
			)
			(placement
				(enabled no)
				(sheetname "")
			)
			(fill
				(thermal_gap 0.5)
				(thermal_bridge_width 0.5)
				(island_removal_mode 0)
			)
			(polygon
				(pts
					(xy 181.737 -12.954) (xy 182.245 -12.954) (xy 182.245 -13.335) (xy 181.737 -13.335)
				)
			)
		)
	)
	(footprint ""
		(layer "B.Cu")
		(at 17.272 -90.805)
		(property "Reference" "C9W1"
			(at 0 0 0)
			(layer "B.SilkS")
			(hide yes)
			(effects
				(font
					(size 1.27 1.27)
				)
				(justify mirror)
			)
		)
		(property "Value" "*"
			(at -1.1811 -2.8194 0)
			(unlocked yes)
			(layer "B.Fab")
			(hide yes)
			(effects
				(font
					(size 1.27 1.016)
					(thickness 0.1524)
				)
				(justify mirror)
			)
		)
		(property "Device Type" "SC22P50V2JN-4GP_SMD-BCG-SC22P5A"
			(at -1.1811 -4.3434 0)
			(unlocked yes)
			(layer "B.Fab")
			(hide yes)
			(effects
				(font
					(size 1.27 1.016)
					(thickness 0.1524)
				)
				(justify mirror)
			)
		)
		(duplicate_pad_numbers_are_jumpers no)
		(fp_rect
			(start 0.4318 0.9525)
			(end -0.4318 -0.9525)
			(stroke
				(width 0)
				(type default)
			)
			(fill no)
			(layer "B.CrtYd")
		)
		(fp_rect
			(start 0.4318 0.9525)
			(end -0.4318 -0.9525)
			(stroke
				(width 0)
				(type default)
			)
			(fill no)
			(layer "B.Fab")
		)
		(pad "1" smd custom
			(at 0 -0.4445 180)
			(size 0.1524 0.1524)
			(layers "B.Cu" "B.Mask" "B.Paste")
			(net "A_P12V_STBY_FP_TRIGGER")
			(options
				(clearance outline)
				(anchor circle)
			)
			(primitives
				(gr_poly
					(pts
						(arc
							(start 0.3048 0.2032)
							(mid 0.275042 0.275042)
							(end 0.2032 0.3048)
						)
						(arc
							(start -0.2032 0.3048)
							(mid -0.275042 0.275042)
							(end -0.3048 0.2032)
						)
						(arc
							(start -0.3048 -0.2032)
							(mid -0.275042 -0.275042)
							(end -0.2032 -0.3048)
						)
						(arc
							(start 0.2032 -0.3048)
							(mid 0.275042 -0.275042)
							(end 0.3048 -0.2032)
						)
					)
					(width 0)
					(fill yes)
				)
			)
		)
		(pad "2" smd custom
			(at 0 0.4445 180)
			(size 0.1524 0.1524)
			(layers "B.Cu" "B.Mask" "B.Paste")
			(net "AGND_HSC")
			(options
				(clearance outline)
				(anchor circle)
			)
			(primitives
				(gr_poly
					(pts
						(arc
							(start 0.3048 0.2032)
							(mid 0.275042 0.275042)
							(end 0.2032 0.3048)
						)
						(arc
							(start -0.2032 0.3048)
							(mid -0.275042 0.275042)
							(end -0.3048 0.2032)
						)
						(arc
							(start -0.3048 -0.2032)
							(mid -0.275042 -0.275042)
							(end -0.2032 -0.3048)
						)
						(arc
							(start 0.2032 -0.3048)
							(mid 0.275042 -0.275042)
							(end 0.3048 -0.2032)
						)
					)
					(width 0)
					(fill yes)
				)
			)
		)
	)
)
